(kicad_pcb
	(version 20260206)
	(generator "pcbnew")
	(generator_version "10.0")
	(general
		(thickness 1.6)
		(legacy_teardrops no)
	)
	(paper "A4")
	(title_block
		(title "03242023_DA0F0TMBIJ0_F0T_Motherboard_J_brd_V01_OCP.brd")
		(comment 1 "Grand Teton / footprints 2932-2938 of 6105")
	)
	(layers
		(0 "F.Cu" signal "TOP")
		(4 "In1.Cu" signal "GND")
		(6 "In2.Cu" signal "IN1")
		(8 "In3.Cu" signal "GND1")
		(10 "In4.Cu" signal "IN2")
		(12 "In5.Cu" signal "GND2")
		(14 "In6.Cu" signal "IN3")
		(16 "In7.Cu" signal "GND3")
		(18 "In8.Cu" signal "VCC")
		(20 "In9.Cu" signal "VCC1")
		(22 "In10.Cu" signal "GND4")
		(24 "In11.Cu" signal "IN4")
		(26 "In12.Cu" signal "GND5")
		(28 "In13.Cu" signal "IN5")
		(30 "In14.Cu" signal "GND6")
		(32 "In15.Cu" signal "IN6")
		(34 "In16.Cu" signal "GND7")
		(2 "B.Cu" signal "BOTTOM")
		(9 "F.Adhes" user "F.Adhesive")
		(11 "B.Adhes" user "B.Adhesive")
		(13 "F.Paste" user "Package Geometry/Pastemask Top")
		(15 "B.Paste" user "Package Geometry/Pastemask Bottom")
		(5 "F.SilkS" user "Ref Des/Silkscreen Top")
		(7 "B.SilkS" user "Ref Des/Silkscreen Bottom")
		(1 "F.Mask" user "Board Geometry/Soldermask Top")
		(3 "B.Mask" user "Board Geometry/Soldermask Bottom")
		(17 "Dwgs.User" user "User.Drawings")
		(19 "Cmts.User" user "User.Comments")
		(21 "Eco1.User" user "User.Eco1")
		(23 "Eco2.User" user "User.Eco2")
		(25 "Edge.Cuts" user "Board Geometry/Outline")
		(27 "Margin" user)
		(31 "F.CrtYd" user "Package Geometry/Place Bound Top")
		(29 "B.CrtYd" user "Package Geometry/Place Bound Bottom")
		(35 "F.Fab" user "Ref Des/Assembly Top")
		(33 "B.Fab" user "Ref Des/Assembly Bottom")
	)
	(footprint ""
		(layer "F.Cu")
		(at 344.764106 -389.052816)
		(property "Reference" "ME18"
			(at 0 0 0)
			(layer "F.SilkS")
			(hide yes)
			(effects
				(font
					(size 1.27 1.27)
				)
			)
		)
		(property "Value" ""
			(at 0 0 0)
			(layer "F.Fab")
			(effects
				(font
					(size 1.27 1.27)
				)
			)
		)
		(duplicate_pad_numbers_are_jumpers no)
		(fp_rect
			(start 0 0)
			(end 3.3401 -0.5842)
			(stroke
				(width 0)
				(type default)
			)
			(fill yes)
			(layer "F.SilkS")
		)
		(fp_rect
			(start 1.32715 -3.2512)
			(end 2.01295 -3.4417)
			(stroke
				(width 0)
				(type default)
			)
			(fill yes)
			(layer "F.SilkS")
		)
		(fp_poly
			(pts
				(xy 0.92075 -1.1557) (xy 0.888492 -1.51384) (xy 0.094488 -0.693928) (xy -0.070612 -0.681228) (xy -0.197612 -0.820928)
				(xy 0.852678 -1.91262) (xy 0.728472 -3.29184) (xy -0.248412 -4.300728) (xy -0.184912 -4.478528)
				(xy -0.007112 -4.503928) (xy 0.684022 -3.785616) (xy 0.65659 -4.0894) (xy 0.97155 -4.3434) (xy 1.22555 -4.3561)
				(xy 1.46685 -4.4704) (xy 2.01295 -4.4704) (xy 2.15265 -4.4069) (xy 2.44475 -4.191) (xy 2.49555 -4.191)
				(xy 2.59715 -4.2926) (xy 2.80035 -4.2672) (xy 2.88925 -4.1656) (xy 2.88925 -4.029456) (xy 3.345688 -4.503928)
				(xy 3.523488 -4.478528) (xy 3.586988 -4.300728) (xy 2.88925 -3.58013) (xy 2.88925 -3.3147) (xy 2.82575 -3.2385)
				(xy 2.67335 -3.2385) (xy 2.521966 -1.875282) (xy 2.545842 -1.85039)
				(arc
					(start 2.55905 -1.8415)
					(mid 2.648099 -1.766068)
					(end 2.717292 -1.672082)
				)
				(xy 3.536188 -0.820928) (xy 3.409188 -0.681228) (xy 3.244088 -0.693928)
				(arc
					(start 2.737612 -1.216914)
					(mid 2.31728 -0.925553)
					(end 1.86055 -1.1557)
				)
			)
			(stroke
				(width 0)
				(type default)
			)
			(fill yes)
			(layer "F.SilkS")
		)
	)
	(footprint ""
		(layer "F.Cu")
		(at 328.460608 -402.371052 -90)
		(property "Reference" "C1794"
			(at 0 0 270)
			(layer "F.SilkS")
			(hide yes)
			(effects
				(font
					(size 1.27 1.27)
				)
			)
		)
		(property "Value" ""
			(at 0 0 270)
			(layer "F.Fab")
			(effects
				(font
					(size 1.27 1.27)
				)
			)
		)
		(duplicate_pad_numbers_are_jumpers no)
		(fp_line
			(start -0.299974 0.150114)
			(end -0.299974 -0.150114)
			(stroke
				(width 0.1)
				(type default)
			)
			(layer "F.Fab")
		)
		(fp_line
			(start 0.299974 0.150114)
			(end -0.299974 0.150114)
			(stroke
				(width 0.1)
				(type default)
			)
			(layer "F.Fab")
		)
		(fp_line
			(start -0.299974 -0.150114)
			(end 0.299974 -0.150114)
			(stroke
				(width 0.1)
				(type default)
			)
			(layer "F.Fab")
		)
		(fp_line
			(start 0.299974 -0.150114)
			(end 0.299974 0.150114)
			(stroke
				(width 0.1)
				(type default)
			)
			(layer "F.Fab")
		)
		(pad "1" smd rect
			(at -0.2667 0 270)
			(size 0.3048 0.381)
			(layers "F.Cu" "F.Mask" "F.Paste")
			(net "P5E_CPU0_PE4_TX_C_DN<8>")
		)
		(pad "2" smd rect
			(at 0.2667 0 270)
			(size 0.3048 0.381)
			(layers "F.Cu" "F.Mask" "F.Paste")
			(net "P5E_CPU0_PE4_TX_DN<8>")
		)
	)
	(footprint ""
		(layer "F.Cu")
		(at 336.779108 -16.219678 -90)
		(property "Reference" "C607"
			(at 0 0 270)
			(layer "F.SilkS")
			(hide yes)
			(effects
				(font
					(size 1.27 1.27)
				)
			)
		)
		(property "Value" ""
			(at 0 0 270)
			(layer "F.Fab")
			(effects
				(font
					(size 1.27 1.27)
				)
			)
		)
		(duplicate_pad_numbers_are_jumpers no)
		(fp_line
			(start -0.7874 0.4064)
			(end -0.7874 -0.4064)
			(stroke
				(width 0.1524)
				(type default)
			)
			(layer "F.SilkS")
		)
		(fp_line
			(start 0.7874 0.4064)
			(end -0.7874 0.4064)
			(stroke
				(width 0.1524)
				(type default)
			)
			(layer "F.SilkS")
		)
		(fp_line
			(start -0.7874 -0.4064)
			(end 0.7874 -0.4064)
			(stroke
				(width 0.1524)
				(type default)
			)
			(layer "F.SilkS")
		)
		(fp_line
			(start 0.7874 -0.4064)
			(end 0.7874 0.4064)
			(stroke
				(width 0.1524)
				(type default)
			)
			(layer "F.SilkS")
		)
		(fp_line
			(start -0.67945 0.3048)
			(end -0.67945 -0.305054)
			(stroke
				(width 0.1)
				(type default)
			)
			(layer "F.Fab")
		)
		(fp_line
			(start -0.12065 0.3048)
			(end -0.67945 0.3048)
			(stroke
				(width 0.1)
				(type default)
			)
			(layer "F.Fab")
		)
		(fp_line
			(start 0.120396 0.3048)
			(end 0.120396 0.2794)
			(stroke
				(width 0.1)
				(type default)
			)
			(layer "F.Fab")
		)
		(fp_line
			(start 0.67945 0.3048)
			(end 0.120396 0.3048)
			(stroke
				(width 0.1)
				(type default)
			)
			(layer "F.Fab")
		)
		(fp_line
			(start -0.12065 0.2794)
			(end -0.12065 0.3048)
			(stroke
				(width 0.1)
				(type default)
			)
			(layer "F.Fab")
		)
		(fp_line
			(start 0.120396 0.2794)
			(end -0.12065 0.2794)
			(stroke
				(width 0.1)
				(type default)
			)
			(layer "F.Fab")
		)
		(fp_line
			(start -0.12065 -0.2794)
			(end 0.12065 -0.2794)
			(stroke
				(width 0.1)
				(type default)
			)
			(layer "F.Fab")
		)
		(fp_line
			(start 0.12065 -0.2794)
			(end 0.12065 -0.3048)
			(stroke
				(width 0.1)
				(type default)
			)
			(layer "F.Fab")
		)
		(fp_line
			(start 0.12065 -0.3048)
			(end 0.67945 -0.3048)
			(stroke
				(width 0.1)
				(type default)
			)
			(layer "F.Fab")
		)
		(fp_line
			(start 0.67945 -0.3048)
			(end 0.67945 0.3048)
			(stroke
				(width 0.1)
				(type default)
			)
			(layer "F.Fab")
		)
		(fp_line
			(start -0.67945 -0.305054)
			(end -0.12065 -0.305054)
			(stroke
				(width 0.1)
				(type default)
			)
			(layer "F.Fab")
		)
		(fp_line
			(start -0.12065 -0.305054)
			(end -0.12065 -0.2794)
			(stroke
				(width 0.1)
				(type default)
			)
			(layer "F.Fab")
		)
		(pad "1" smd circle
			(at -0.40005 0 270)
			(size 0 0)
			(layers "F.Cu" "F.Mask" "F.Paste")
			(net "PGPPA_AUX")
		)
		(pad "2" smd circle
			(at 0.40005 0 270)
			(size 0 0)
			(layers "F.Cu" "F.Mask" "F.Paste")
			(net "GND")
		)
	)
	(footprint ""
		(layer "F.Cu")
		(at 224.2312 -49.71288 180)
		(property "Reference" "R4083"
			(at 0 0 180)
			(layer "F.SilkS")
			(hide yes)
			(effects
				(font
					(size 1.27 1.27)
				)
			)
		)
		(property "Value" ""
			(at 0 0 180)
			(layer "F.Fab")
			(effects
				(font
					(size 1.27 1.27)
				)
			)
		)
		(duplicate_pad_numbers_are_jumpers no)
		(fp_line
			(start 0.7874 0.4064)
			(end -0.7874 0.4064)
			(stroke
				(width 0.1524)
				(type default)
			)
			(layer "F.SilkS")
		)
		(fp_line
			(start 0.7874 -0.4064)
			(end 0.7874 0.4064)
			(stroke
				(width 0.1524)
				(type default)
			)
			(layer "F.SilkS")
		)
		(fp_line
			(start -0.7874 0.4064)
			(end -0.7874 -0.4064)
			(stroke
				(width 0.1524)
				(type default)
			)
			(layer "F.SilkS")
		)
		(fp_line
			(start -0.7874 -0.4064)
			(end 0.7874 -0.4064)
			(stroke
				(width 0.1524)
				(type default)
			)
			(layer "F.SilkS")
		)
		(fp_line
			(start 0.67945 0.3048)
			(end 0.120396 0.3048)
			(stroke
				(width 0.1)
				(type default)
			)
			(layer "F.Fab")
		)
		(fp_line
			(start 0.67945 -0.3048)
			(end 0.67945 0.3048)
			(stroke
				(width 0.1)
				(type default)
			)
			(layer "F.Fab")
		)
		(fp_line
			(start 0.12065 -0.2794)
			(end 0.12065 -0.3048)
			(stroke
				(width 0.1)
				(type default)
			)
			(layer "F.Fab")
		)
		(fp_line
			(start 0.12065 -0.3048)
			(end 0.67945 -0.3048)
			(stroke
				(width 0.1)
				(type default)
			)
			(layer "F.Fab")
		)
		(fp_line
			(start 0.120396 0.3048)
			(end 0.120396 0.2794)
			(stroke
				(width 0.1)
				(type default)
			)
			(layer "F.Fab")
		)
		(fp_line
			(start 0.120396 0.2794)
			(end -0.12065 0.2794)
			(stroke
				(width 0.1)
				(type default)
			)
			(layer "F.Fab")
		)
		(fp_line
			(start -0.12065 0.3048)
			(end -0.67945 0.3048)
			(stroke
				(width 0.1)
				(type default)
			)
			(layer "F.Fab")
		)
		(fp_line
			(start -0.12065 0.2794)
			(end -0.12065 0.3048)
			(stroke
				(width 0.1)
				(type default)
			)
			(layer "F.Fab")
		)
		(fp_line
			(start -0.12065 -0.2794)
			(end 0.12065 -0.2794)
			(stroke
				(width 0.1)
				(type default)
			)
			(layer "F.Fab")
		)
		(fp_line
			(start -0.12065 -0.305054)
			(end -0.12065 -0.2794)
			(stroke
				(width 0.1)
				(type default)
			)
			(layer "F.Fab")
		)
		(fp_line
			(start -0.67945 0.3048)
			(end -0.67945 -0.305054)
			(stroke
				(width 0.1)
				(type default)
			)
			(layer "F.Fab")
		)
		(fp_line
			(start -0.67945 -0.305054)
			(end -0.12065 -0.305054)
			(stroke
				(width 0.1)
				(type default)
			)
			(layer "F.Fab")
		)
		(pad "1" smd circle
			(at -0.40005 0 180)
			(size 0 0)
			(layers "F.Cu" "F.Mask" "F.Paste")
			(net "E1S_0_PERST1_CLKREQ_N")
		)
		(pad "2" smd circle
			(at 0.40005 0 180)
			(size 0 0)
			(layers "F.Cu" "F.Mask" "F.Paste")
			(net "E1S_0_CLKREQ_N")
		)
	)
	(footprint ""
		(layer "F.Cu")
		(at 36.801298 -182.28564)
		(property "Reference" "PC1207"
			(at 0 0 0)
			(layer "F.SilkS")
			(hide yes)
			(effects
				(font
					(size 1.27 1.27)
				)
			)
		)
		(property "Value" ""
			(at 0 0 0)
			(layer "F.Fab")
			(effects
				(font
					(size 1.27 1.27)
				)
			)
		)
		(duplicate_pad_numbers_are_jumpers no)
		(fp_line
			(start -1.524 -0.762)
			(end 1.524 -0.762)
			(stroke
				(width 0.1524)
				(type default)
			)
			(layer "F.SilkS")
		)
		(fp_line
			(start -1.524 0.762)
			(end -1.524 -0.762)
			(stroke
				(width 0.1524)
				(type default)
			)
			(layer "F.SilkS")
		)
		(fp_line
			(start 1.524 -0.762)
			(end 1.524 0.762)
			(stroke
				(width 0.1524)
				(type default)
			)
			(layer "F.SilkS")
		)
		(fp_line
			(start 1.524 0.762)
			(end -1.524 0.762)
			(stroke
				(width 0.1524)
				(type default)
			)
			(layer "F.SilkS")
		)
		(fp_line
			(start -1.1049 -0.724916)
			(end -1.1049 0.724916)
			(stroke
				(width 0.1)
				(type default)
			)
			(layer "F.Fab")
		)
		(fp_line
			(start -1.1049 0.724916)
			(end 1.1049 0.724916)
			(stroke
				(width 0.1)
				(type default)
			)
			(layer "F.Fab")
		)
		(fp_line
			(start 1.1049 -0.724916)
			(end -1.1049 -0.724916)
			(stroke
				(width 0.1)
				(type default)
			)
			(layer "F.Fab")
		)
		(fp_line
			(start 1.1049 0.724916)
			(end 1.1049 -0.724916)
			(stroke
				(width 0.1)
				(type default)
			)
			(layer "F.Fab")
		)
		(pad "1" smd rect
			(at -0.889 0 180)
			(size 1.016 1.27)
			(layers "F.Cu" "F.Mask" "F.Paste")
			(net "PVNN_MAIN_CPU1")
		)
		(pad "2" smd rect
			(at 0.889 0 180)
			(size 1.016 1.27)
			(layers "F.Cu" "F.Mask" "F.Paste")
			(net "GND")
		)
	)
	(footprint ""
		(layer "F.Cu")
		(at 292.357302 -362.843826 -90)
		(property "Reference" "PC1176_P0_4"
			(at 0 0 270)
			(layer "F.SilkS")
			(hide yes)
			(effects
				(font
					(size 1.27 1.27)
				)
			)
		)
		(property "Value" ""
			(at 0 0 270)
			(layer "F.Fab")
			(effects
				(font
					(size 1.27 1.27)
				)
			)
		)
		(duplicate_pad_numbers_are_jumpers no)
		(fp_line
			(start -0.7874 0.4064)
			(end -0.7874 -0.4064)
			(stroke
				(width 0.1524)
				(type default)
			)
			(layer "F.SilkS")
		)
		(fp_line
			(start 0.7874 0.4064)
			(end -0.7874 0.4064)
			(stroke
				(width 0.1524)
				(type default)
			)
			(layer "F.SilkS")
		)
		(fp_line
			(start -0.7874 -0.4064)
			(end 0.7874 -0.4064)
			(stroke
				(width 0.1524)
				(type default)
			)
			(layer "F.SilkS")
		)
		(fp_line
			(start 0.7874 -0.4064)
			(end 0.7874 0.4064)
			(stroke
				(width 0.1524)
				(type default)
			)
			(layer "F.SilkS")
		)
		(fp_line
			(start -0.67945 0.3048)
			(end -0.67945 -0.305054)
			(stroke
				(width 0.1)
				(type default)
			)
			(layer "F.Fab")
		)
		(fp_line
			(start -0.12065 0.3048)
			(end -0.67945 0.3048)
			(stroke
				(width 0.1)
				(type default)
			)
			(layer "F.Fab")
		)
		(fp_line
			(start 0.120396 0.3048)
			(end 0.120396 0.2794)
			(stroke
				(width 0.1)
				(type default)
			)
			(layer "F.Fab")
		)
		(fp_line
			(start 0.67945 0.3048)
			(end 0.120396 0.3048)
			(stroke
				(width 0.1)
				(type default)
			)
			(layer "F.Fab")
		)
		(fp_line
			(start -0.12065 0.2794)
			(end -0.12065 0.3048)
			(stroke
				(width 0.1)
				(type default)
			)
			(layer "F.Fab")
		)
		(fp_line
			(start 0.120396 0.2794)
			(end -0.12065 0.2794)
			(stroke
				(width 0.1)
				(type default)
			)
			(layer "F.Fab")
		)
		(fp_line
			(start -0.12065 -0.2794)
			(end 0.12065 -0.2794)
			(stroke
				(width 0.1)
				(type default)
			)
			(layer "F.Fab")
		)
		(fp_line
			(start 0.12065 -0.2794)
			(end 0.12065 -0.3048)
			(stroke
				(width 0.1)
				(type default)
			)
			(layer "F.Fab")
		)
		(fp_line
			(start 0.12065 -0.3048)
			(end 0.67945 -0.3048)
			(stroke
				(width 0.1)
				(type default)
			)
			(layer "F.Fab")
		)
		(fp_line
			(start 0.67945 -0.3048)
			(end 0.67945 0.3048)
			(stroke
				(width 0.1)
				(type default)
			)
			(layer "F.Fab")
		)
		(fp_line
			(start -0.67945 -0.305054)
			(end -0.12065 -0.305054)
			(stroke
				(width 0.1)
				(type default)
			)
			(layer "F.Fab")
		)
		(fp_line
			(start -0.12065 -0.305054)
			(end -0.12065 -0.2794)
			(stroke
				(width 0.1)
				(type default)
			)
			(layer "F.Fab")
		)
		(pad "1" smd circle
			(at -0.40005 0 270)
			(size 0 0)
			(layers "F.Cu" "F.Mask" "F.Paste")
			(net "SW_P12V_PVCCFA_EHV_FIVRA_CPU0_L")
		)
		(pad "2" smd circle
			(at 0.40005 0 270)
			(size 0 0)
			(layers "F.Cu" "F.Mask" "F.Paste")
			(net "GND")
		)
	)
	(footprint ""
		(layer "F.Cu")
		(at 335.48574 -342.270334)
		(property "Reference" "PR138"
			(at 0 0 0)
			(layer "F.SilkS")
			(hide yes)
			(effects
				(font
					(size 1.27 1.27)
				)
			)
		)
		(property "Value" ""
			(at 0 0 0)
			(layer "F.Fab")
			(effects
				(font
					(size 1.27 1.27)
				)
			)
		)
		(duplicate_pad_numbers_are_jumpers no)
		(fp_line
			(start -0.7874 -0.4064)
			(end 0.7874 -0.4064)
			(stroke
				(width 0.1524)
				(type default)
			)
			(layer "F.SilkS")
		)
		(fp_line
			(start -0.7874 0.4064)
			(end -0.7874 -0.4064)
			(stroke
				(width 0.1524)
				(type default)
			)
			(layer "F.SilkS")
		)
		(fp_line
			(start 0.7874 -0.4064)
			(end 0.7874 0.4064)
			(stroke
				(width 0.1524)
				(type default)
			)
			(layer "F.SilkS")
		)
		(fp_line
			(start 0.7874 0.4064)
			(end -0.7874 0.4064)
			(stroke
				(width 0.1524)
				(type default)
			)
			(layer "F.SilkS")
		)
		(fp_line
			(start -0.67945 -0.305054)
			(end -0.12065 -0.305054)
			(stroke
				(width 0.1)
				(type default)
			)
			(layer "F.Fab")
		)
		(fp_line
			(start -0.67945 0.3048)
			(end -0.67945 -0.305054)
			(stroke
				(width 0.1)
				(type default)
			)
			(layer "F.Fab")
		)
		(fp_line
			(start -0.12065 -0.305054)
			(end -0.12065 -0.2794)
			(stroke
				(width 0.1)
				(type default)
			)
			(layer "F.Fab")
		)
		(fp_line
			(start -0.12065 -0.2794)
			(end 0.12065 -0.2794)
			(stroke
				(width 0.1)
				(type default)
			)
			(layer "F.Fab")
		)
		(fp_line
			(start -0.12065 0.2794)
			(end -0.12065 0.3048)
			(stroke
				(width 0.1)
				(type default)
			)
			(layer "F.Fab")
		)
		(fp_line
			(start -0.12065 0.3048)
			(end -0.67945 0.3048)
			(stroke
				(width 0.1)
				(type default)
			)
			(layer "F.Fab")
		)
		(fp_line
			(start 0.120396 0.2794)
			(end -0.12065 0.2794)
			(stroke
				(width 0.1)
				(type default)
			)
			(layer "F.Fab")
		)
		(fp_line
			(start 0.120396 0.3048)
			(end 0.120396 0.2794)
			(stroke
				(width 0.1)
				(type default)
			)
			(layer "F.Fab")
		)
		(fp_line
			(start 0.12065 -0.3048)
			(end 0.67945 -0.3048)
			(stroke
				(width 0.1)
				(type default)
			)
			(layer "F.Fab")
		)
		(fp_line
			(start 0.12065 -0.2794)
			(end 0.12065 -0.3048)
			(stroke
				(width 0.1)
				(type default)
			)
			(layer "F.Fab")
		)
		(fp_line
			(start 0.67945 -0.3048)
			(end 0.67945 0.3048)
			(stroke
				(width 0.1)
				(type default)
			)
			(layer "F.Fab")
		)
		(fp_line
			(start 0.67945 0.3048)
			(end 0.120396 0.3048)
			(stroke
				(width 0.1)
				(type default)
			)
			(layer "F.Fab")
		)
		(pad "1" smd circle
			(at -0.40005 0)
			(size 0 0)
			(layers "F.Cu" "F.Mask" "F.Paste")
			(net "PVCCIN_CPU0_LSET6")
		)
		(pad "2" smd circle
			(at 0.40005 0)
			(size 0 0)
			(layers "F.Cu" "F.Mask" "F.Paste")
			(net "GND")
		)
	)
)
